#ISCELL
  logical_power cad_note *
  *
#ISCELL
  mstr_misc dns *
  *
#ISCELL
  pure_quanta quanta_title_block_c *
  *
#ISCELL
  logical_power universal_power *
  page228_i1
#ISCELL
  standard offpage *
  page228_i10
#ISCELL
  standard offpage *
  page228_i100
#ISCELL
  standard offpage *
  page228_i101
#ISCELL
  standard offpage *
  page228_i11
#ISCELL
  standard offpage *
  page228_i12
#ISCELL
  standard offpage *
  page228_i13
#ISCELL
  standard offpage *
  page228_i16
#ISCELL
  standard offpage *
  page228_i17
#CELL
  pure_quanta q_res *
  page228_i172
#CELL
  pure_quanta q_res *
  page228_i173
#CELL
  pure_quanta q_res *
  page228_i176
#CELL
  pure_quanta q_res *
  page228_i177
#ISCELL
  standard offpage *
  page228_i178
#ISCELL
  standard offpage *
  page228_i179
#ISCELL
  standard offpage *
  page228_i18
#ISCELL
  standard offpage *
  page228_i182
#ISCELL
  standard offpage *
  page228_i183
#ISCELL
  standard offpage *
  page228_i19
#ISCELL
  standard offpage *
  page228_i199
#CELL
  pure_quanta q_res *
  page228_i2
#ISCELL
  standard offpage *
  page228_i20
#ISCELL
  standard offpage *
  page228_i201
#CELL
  pure_quanta q_res *
  page228_i202
#CELL
  pure_quanta q_res *
  page228_i203
#ISCELL
  standard offpage *
  page228_i204
#ISCELL
  standard offpage *
  page228_i205
#CELL
  pure_quanta q_res *
  page228_i206
#CELL
  pure_quanta q_res *
  page228_i207
#ISCELL
  standard offpage *
  page228_i208
#ISCELL
  standard offpage *
  page228_i209
#ISCELL
  standard offpage *
  page228_i21
#ISCELL
  standard offpage *
  page228_i210
#ISCELL
  standard offpage *
  page228_i211
#ISCELL
  standard offpage *
  page228_i214
#ISCELL
  standard offpage *
  page228_i215
#CELL
  pure_quanta q_res *
  page228_i216
#CELL
  pure_quanta q_res *
  page228_i217
#CELL
  pure_quanta q_res *
  page228_i218
#CELL
  pure_quanta q_res *
  page228_i219
#ISCELL
  standard offpage *
  page228_i22
#ISCELL
  standard offpage *
  page228_i226
#ISCELL
  standard offpage *
  page228_i227
#CELL
  pure_quanta q_res *
  page228_i228
#CELL
  pure_quanta q_res *
  page228_i229
#ISCELL
  standard offpage *
  page228_i23
#CELL
  pure_quanta q_res *
  page228_i230
#CELL
  pure_quanta q_res *
  page228_i231
#ISCELL
  standard offpage *
  page228_i232
#ISCELL
  standard offpage *
  page228_i233
#CELL
  pure_quanta q_res *
  page228_i234
#ISCELL
  standard offpage *
  page228_i235
#ISCELL
  standard offpage *
  page228_i236
#CELL
  pure_quanta q_res *
  page228_i237
#ISCELL
  standard offpage *
  page228_i238
#ISCELL
  standard offpage *
  page228_i239
#ISCELL
  standard offpage *
  page228_i240
#ISCELL
  standard offpage *
  page228_i241
#CELL
  pure_quanta q_res *
  page228_i242
#CELL
  pure_quanta q_res *
  page228_i243
#CELL
  pure_quanta q_res *
  page228_i250
#CELL
  pure_quanta q_res *
  page228_i251
#ISCELL
  standard offpage *
  page228_i252
#ISCELL
  standard offpage *
  page228_i253
#ISCELL
  standard offpage *
  page228_i254
#ISCELL
  standard offpage *
  page228_i255
#ISCELL
  standard offpage *
  page228_i256
#ISCELL
  standard offpage *
  page228_i257
#CELL
  pure_quanta q_res *
  page228_i258
#CELL
  pure_quanta q_res *
  page228_i259
#CELL
  pure_quanta q_res *
  page228_i260
#CELL
  pure_quanta q_res *
  page228_i261
#ISCELL
  standard offpage *
  page228_i262
#ISCELL
  standard offpage *
  page228_i263
#CELL
  pure_quanta q_res *
  page228_i264
#ISCELL
  standard offpage *
  page228_i266
#ISCELL
  standard offpage *
  page228_i267
#CELL
  pure_quanta q_res *
  page228_i268
#ISCELL
  standard offpage *
  page228_i269
#ISCELL
  standard offpage *
  page228_i270
#CELL
  pure_quanta q_res *
  page228_i271
#CELL
  pure_quanta q_res *
  page228_i272
#CELL
  pure_quanta q_res *
  page228_i273
#CELL
  pure_quanta q_res *
  page228_i274
#ISCELL
  standard offpage *
  page228_i275
#ISCELL
  standard offpage *
  page228_i276
#ISCELL
  standard offpage *
  page228_i277
#ISCELL
  standard offpage *
  page228_i278
#ISCELL
  standard offpage *
  page228_i28
#CELL
  pure_quanta q_res *
  page228_i284
#CELL
  pure_quanta q_res *
  page228_i285
#ISCELL
  standard offpage *
  page228_i286
#ISCELL
  standard offpage *
  page228_i287
#ISCELL
  standard offpage *
  page228_i288
#ISCELL
  standard offpage *
  page228_i289
#ISCELL
  standard offpage *
  page228_i29
#ISCELL
  standard offpage *
  page228_i290
#ISCELL
  standard offpage *
  page228_i291
#CELL
  pure_quanta q_res *
  page228_i293
#ISCELL
  standard offpage *
  page228_i294
#ISCELL
  standard offpage *
  page228_i295
#CELL
  pure_quanta q_res *
  page228_i296
#ISCELL
  standard offpage *
  page228_i299
#CELL
  pure_quanta q_res *
  page228_i3
#ISCELL
  standard offpage *
  page228_i30
#ISCELL
  standard offpage *
  page228_i300
#ISCELL
  standard offpage *
  page228_i301
#ISCELL
  standard offpage *
  page228_i302
#CELL
  pure_quanta q_res *
  page228_i303
#CELL
  pure_quanta q_res *
  page228_i304
#CELL
  pure_quanta q_res *
  page228_i305
#CELL
  pure_quanta q_res *
  page228_i306
#ISCELL
  standard offpage *
  page228_i307
#ISCELL
  standard offpage *
  page228_i308
#ISCELL
  standard offpage *
  page228_i309
#ISCELL
  standard offpage *
  page228_i31
#ISCELL
  standard offpage *
  page228_i310
#CELL
  pure_quanta q_res *
  page228_i311
#CELL
  pure_quanta q_res *
  page228_i312
#CELL
  pure_quanta q_res *
  page228_i313
#CELL
  pure_quanta q_res *
  page228_i314
#CELL
  pure_quanta q_res *
  page228_i315
#CELL
  pure_quanta q_res *
  page228_i316
#CELL
  pure_quanta q_res *
  page228_i317
#CELL
  pure_quanta q_res *
  page228_i318
#ISCELL
  standard offpage *
  page228_i32
#ISCELL
  standard offpage *
  page228_i33
#ISCELL
  standard offpage *
  page228_i34
#ISCELL
  standard offpage *
  page228_i35
#CELL
  pure_quanta q_res *
  page228_i38
#CELL
  pure_quanta q_res *
  page228_i39
#CELL
  pure_quanta q_res *
  page228_i4
#CELL
  pure_quanta q_res *
  page228_i40
#CELL
  pure_quanta q_res *
  page228_i41
#CELL
  pure_quanta q_res *
  page228_i42
#CELL
  pure_quanta q_res *
  page228_i43
#CELL
  pure_quanta q_res *
  page228_i44
#CELL
  pure_quanta q_res *
  page228_i45
#CELL
  pure_quanta q_res *
  page228_i5
#ISCELL
  standard offpage *
  page228_i52
#ISCELL
  standard offpage *
  page228_i53
#ISCELL
  standard offpage *
  page228_i54
#ISCELL
  standard offpage *
  page228_i55
#ISCELL
  standard offpage *
  page228_i56
#ISCELL
  standard offpage *
  page228_i57
#CELL
  pure_quanta q_res *
  page228_i6
#ISCELL
  standard offpage *
  page228_i66
#ISCELL
  standard offpage *
  page228_i67
#ISCELL
  standard offpage *
  page228_i68
#ISCELL
  standard offpage *
  page228_i69
#CELL
  pure_quanta q_res *
  page228_i7
#ISCELL
  standard offpage *
  page228_i70
#ISCELL
  standard offpage *
  page228_i71
#ISCELL
  standard offpage *
  page228_i72
#ISCELL
  standard offpage *
  page228_i73
#ISCELL
  standard offpage *
  page228_i8
#CELL
  pure_quanta q_res *
  page228_i89
#ISCELL
  standard offpage *
  page228_i9
#CELL
  pure_quanta q_res *
  page228_i90
#ISCELL
  standard offpage *
  page228_i91
#ISCELL
  standard offpage *
  page228_i92
